(kicad_pcb
	(version 20260206)
	(generator "pcbnew")
	(generator_version "10.0")
	(general
		(thickness 1.6)
		(legacy_teardrops no)
	)
	(paper "A4")
	(title_block
		(title "peb — Lightning_PEB_BRD.brd")
		(comment 1 "Lightning (Wiwynn / Facebook NVMe JBOF) / footprints 423-430 of 2563")
	)
	(layers
		(0 "F.Cu" signal "TOP")
		(4 "In1.Cu" signal "L2GND")
		(6 "In2.Cu" signal "L3")
		(8 "In3.Cu" signal "L4VCC")
		(10 "In4.Cu" signal "L5VCC")
		(12 "In5.Cu" signal "L6")
		(14 "In6.Cu" signal "L7GND")
		(2 "B.Cu" signal "BOTTOM")
		(9 "F.Adhes" user "F.Adhesive")
		(11 "B.Adhes" user "B.Adhesive")
		(13 "F.Paste" user "Package Geometry/Pastemask Top")
		(15 "B.Paste" user "Package Geometry/Pastemask Bottom")
		(5 "F.SilkS" user "Ref Des/Silkscreen Top")
		(7 "B.SilkS" user "Ref Des/Silkscreen Bottom")
		(1 "F.Mask" user "Board Geometry/Soldermask Top")
		(3 "B.Mask" user "Board Geometry/Soldermask Bottom")
		(17 "Dwgs.User" user "User.Drawings")
		(19 "Cmts.User" user "User.Comments")
		(21 "Eco1.User" user "User.Eco1")
		(23 "Eco2.User" user "User.Eco2")
		(25 "Edge.Cuts" user "Board Geometry/Outline")
		(27 "Margin" user)
		(31 "F.CrtYd" user "Package Geometry/Place Bound Top")
		(29 "B.CrtYd" user "Package Geometry/Place Bound Bottom")
		(35 "F.Fab" user "Ref Des/Assembly Top")
		(33 "B.Fab" user "Ref Des/Assembly Bottom")
	)
	(footprint ""
		(layer "F.Cu")
		(at 178.1048 -66.167 180)
		(property "Reference" "PG14"
			(at 0 0 180)
			(layer "F.SilkS")
			(hide yes)
			(effects
				(font
					(size 1.27 1.27)
				)
			)
		)
		(property "Value" "GAP-CLOSE-PWR-3-GP"
			(at 0.0254 -6.5786 180)
			(unlocked yes)
			(layer "F.Fab")
			(hide yes)
			(effects
				(font
					(size 1.016 1.016)
					(thickness 0.1524)
				)
			)
		)
		(property "Device Type" "GAP-CLOSE-PWR-3"
			(at 0.0254 -8.255 180)
			(unlocked yes)
			(layer "F.Fab")
			(hide yes)
			(effects
				(font
					(size 1.016 1.016)
					(thickness 0.1524)
				)
			)
		)
		(duplicate_pad_numbers_are_jumpers no)
		(fp_rect
			(start -0.7112 0.4572)
			(end 0.7112 -0.4572)
			(stroke
				(width 0)
				(type default)
			)
			(fill no)
			(layer "F.CrtYd")
		)
		(fp_poly
			(pts
				(xy -0.7112 -0.4572) (xy 0.7112 -0.4572) (xy 0.7112 0.4572) (xy -0.7112 0.4572)
			)
			(stroke
				(width 0)
				(type default)
			)
			(fill no)
			(layer "F.Fab")
		)
		(pad "1" smd rect
			(at -0.3048 0 180)
			(size 0.6604 0.762)
			(layers "F.Cu" "F.Mask" "F.Paste")
			(net "DUT_AVD_PCIE")
		)
		(pad "2" smd rect
			(at 0.3048 0 180)
			(size 0.6604 0.762)
			(layers "F.Cu" "F.Mask" "F.Paste")
			(net "P0V9")
		)
	)
	(footprint ""
		(layer "F.Cu")
		(at 206.60995 -31.402274 90)
		(property "Reference" "R2980"
			(at 0 0 90)
			(layer "F.SilkS")
			(hide yes)
			(effects
				(font
					(size 1.27 1.27)
				)
			)
		)
		(property "Value" "0R2J-2-GP"
			(at 0.064008 -3.993896 90)
			(unlocked yes)
			(layer "F.Fab")
			(hide yes)
			(effects
				(font
					(size 1.016 1.016)
					(thickness 0.1524)
				)
			)
		)
		(property "Device Type" "R402H16"
			(at 0.064008 -5.517896 90)
			(unlocked yes)
			(layer "F.Fab")
			(hide yes)
			(effects
				(font
					(size 1.016 1.016)
					(thickness 0.1524)
				)
			)
		)
		(duplicate_pad_numbers_are_jumpers no)
		(fp_line
			(start 0.508 -0.9398)
			(end -0.508 -0.9398)
			(stroke
				(width 0.1524)
				(type default)
			)
			(layer "F.SilkS")
		)
		(fp_line
			(start -0.508 -0.9398)
			(end -0.508 0.9398)
			(stroke
				(width 0.1524)
				(type default)
			)
			(layer "F.SilkS")
		)
		(fp_rect
			(start -0.508 0.9398)
			(end 0.508 -0.9398)
			(stroke
				(width 0)
				(type default)
			)
			(fill no)
			(layer "F.CrtYd")
		)
		(fp_rect
			(start -0.508 0.9398)
			(end 0.508 -0.9398)
			(stroke
				(width 0)
				(type default)
			)
			(fill no)
			(layer "F.Fab")
		)
		(pad "1" smd custom
			(at 0 -0.4445 90)
			(size 0.1397 0.1397)
			(layers "F.Cu" "F.Mask" "F.Paste")
			(net "U55_SCL")
			(options
				(clearance outline)
				(anchor circle)
			)
			(primitives
				(gr_poly
					(pts
						(arc
							(start -0.1778 -0.2794)
							(mid -0.249642 -0.249642)
							(end -0.2794 -0.1778)
						)
						(arc
							(start -0.2794 0.1778)
							(mid -0.249642 0.249642)
							(end -0.1778 0.2794)
						)
						(arc
							(start 0.1778 0.2794)
							(mid 0.249642 0.249642)
							(end 0.2794 0.1778)
						)
						(arc
							(start 0.2794 -0.1778)
							(mid 0.249642 -0.249642)
							(end 0.1778 -0.2794)
						)
					)
					(width 0)
					(fill yes)
				)
			)
		)
		(pad "2" smd custom
			(at 0 0.4445 90)
			(size 0.1397 0.1397)
			(layers "F.Cu" "F.Mask" "F.Paste")
			(net "BMC_I2C11_MINI5_SCL_S")
			(options
				(clearance outline)
				(anchor circle)
			)
			(primitives
				(gr_poly
					(pts
						(arc
							(start -0.1778 -0.2794)
							(mid -0.249642 -0.249642)
							(end -0.2794 -0.1778)
						)
						(arc
							(start -0.2794 0.1778)
							(mid -0.249642 0.249642)
							(end -0.1778 0.2794)
						)
						(arc
							(start 0.1778 0.2794)
							(mid 0.249642 0.249642)
							(end 0.2794 0.1778)
						)
						(arc
							(start 0.2794 -0.1778)
							(mid 0.249642 -0.249642)
							(end 0.1778 -0.2794)
						)
					)
					(width 0)
					(fill yes)
				)
			)
		)
	)
	(footprint ""
		(layer "F.Cu")
		(at 280.392124 -212.420454 180)
		(property "Reference" "C97"
			(at 0 0 180)
			(layer "F.SilkS")
			(hide yes)
			(effects
				(font
					(size 1.27 1.27)
				)
			)
		)
		(property "Value" "SCD22U10V2KX-1GP"
			(at 1.1811 -2.7051 180)
			(unlocked yes)
			(layer "F.Fab")
			(hide yes)
			(effects
				(font
					(size 1.016 1.016)
					(thickness 0.1524)
				)
			)
		)
		(property "Device Type" "C402H22"
			(at 1.1811 -4.2291 180)
			(unlocked yes)
			(layer "F.Fab")
			(hide yes)
			(effects
				(font
					(size 1.016 1.016)
					(thickness 0.1524)
				)
			)
		)
		(duplicate_pad_numbers_are_jumpers no)
		(fp_rect
			(start -0.4318 0.9525)
			(end 0.4318 -0.9525)
			(stroke
				(width 0)
				(type default)
			)
			(fill no)
			(layer "F.CrtYd")
		)
		(fp_rect
			(start -0.4318 0.9525)
			(end 0.4318 -0.9525)
			(stroke
				(width 0)
				(type default)
			)
			(fill no)
			(layer "F.Fab")
		)
		(pad "1" smd custom
			(at 0 -0.4445 180)
			(size 0.1524 0.1524)
			(layers "F.Cu" "F.Mask" "F.Paste")
			(net "PCIE_TX_CAP_P32")
			(options
				(clearance outline)
				(anchor circle)
			)
			(primitives
				(gr_poly
					(pts
						(arc
							(start 0.3048 -0.2032)
							(mid 0.275042 -0.275042)
							(end 0.2032 -0.3048)
						)
						(arc
							(start -0.2032 -0.3048)
							(mid -0.275042 -0.275042)
							(end -0.3048 -0.2032)
						)
						(arc
							(start -0.3048 0.2032)
							(mid -0.275042 0.275042)
							(end -0.2032 0.3048)
						)
						(arc
							(start 0.2032 0.3048)
							(mid 0.275042 0.275042)
							(end 0.3048 0.2032)
						)
					)
					(width 0)
					(fill yes)
				)
			)
		)
		(pad "2" smd custom
			(at 0 0.4445 180)
			(size 0.1524 0.1524)
			(layers "F.Cu" "F.Mask" "F.Paste")
			(net "PCIE_TX_P32")
			(options
				(clearance outline)
				(anchor circle)
			)
			(primitives
				(gr_poly
					(pts
						(arc
							(start 0.3048 -0.2032)
							(mid 0.275042 -0.275042)
							(end 0.2032 -0.3048)
						)
						(arc
							(start -0.2032 -0.3048)
							(mid -0.275042 -0.275042)
							(end -0.3048 -0.2032)
						)
						(arc
							(start -0.3048 0.2032)
							(mid -0.275042 0.275042)
							(end -0.2032 0.3048)
						)
						(arc
							(start 0.2032 0.3048)
							(mid 0.275042 0.275042)
							(end 0.3048 0.2032)
						)
					)
					(width 0)
					(fill yes)
				)
			)
		)
	)
	(footprint ""
		(layer "F.Cu")
		(at 290.068 -33.528)
		(property "Reference" "C11"
			(at 0 0 0)
			(layer "F.SilkS")
			(hide yes)
			(effects
				(font
					(size 1.27 1.27)
				)
			)
		)
		(property "Value" "SCD22U10V2KX-1GP"
			(at 1.1811 -2.7051 0)
			(unlocked yes)
			(layer "F.Fab")
			(hide yes)
			(effects
				(font
					(size 1.016 1.016)
					(thickness 0.1524)
				)
			)
		)
		(property "Device Type" "C402H22"
			(at 1.1811 -4.2291 0)
			(unlocked yes)
			(layer "F.Fab")
			(hide yes)
			(effects
				(font
					(size 1.016 1.016)
					(thickness 0.1524)
				)
			)
		)
		(duplicate_pad_numbers_are_jumpers no)
		(fp_rect
			(start -0.4318 0.9525)
			(end 0.4318 -0.9525)
			(stroke
				(width 0)
				(type default)
			)
			(fill no)
			(layer "F.CrtYd")
		)
		(fp_rect
			(start -0.4318 0.9525)
			(end 0.4318 -0.9525)
			(stroke
				(width 0)
				(type default)
			)
			(fill no)
			(layer "F.Fab")
		)
		(pad "1" smd custom
			(at 0 -0.4445)
			(size 0.1524 0.1524)
			(layers "F.Cu" "F.Mask" "F.Paste")
			(net "PCIE_TX_CAP_N3")
			(options
				(clearance outline)
				(anchor circle)
			)
			(primitives
				(gr_poly
					(pts
						(arc
							(start 0.3048 -0.2032)
							(mid 0.275042 -0.275042)
							(end 0.2032 -0.3048)
						)
						(arc
							(start -0.2032 -0.3048)
							(mid -0.275042 -0.275042)
							(end -0.3048 -0.2032)
						)
						(arc
							(start -0.3048 0.2032)
							(mid -0.275042 0.275042)
							(end -0.2032 0.3048)
						)
						(arc
							(start 0.2032 0.3048)
							(mid 0.275042 0.275042)
							(end 0.3048 0.2032)
						)
					)
					(width 0)
					(fill yes)
				)
			)
		)
		(pad "2" smd custom
			(at 0 0.4445)
			(size 0.1524 0.1524)
			(layers "F.Cu" "F.Mask" "F.Paste")
			(net "PCIE_TX_N3")
			(options
				(clearance outline)
				(anchor circle)
			)
			(primitives
				(gr_poly
					(pts
						(arc
							(start 0.3048 -0.2032)
							(mid 0.275042 -0.275042)
							(end 0.2032 -0.3048)
						)
						(arc
							(start -0.2032 -0.3048)
							(mid -0.275042 -0.275042)
							(end -0.3048 -0.2032)
						)
						(arc
							(start -0.3048 0.2032)
							(mid -0.275042 0.275042)
							(end -0.2032 0.3048)
						)
						(arc
							(start 0.2032 0.3048)
							(mid 0.275042 0.275042)
							(end 0.3048 0.2032)
						)
					)
					(width 0)
					(fill yes)
				)
			)
		)
	)
	(footprint ""
		(layer "F.Cu")
		(at 134.0993 -33.54324)
		(property "Reference" "C384"
			(at 0 0 0)
			(layer "F.SilkS")
			(hide yes)
			(effects
				(font
					(size 1.27 1.27)
				)
			)
		)
		(property "Value" "SCD22U10V2KX-1GP"
			(at 1.1811 -2.7051 0)
			(unlocked yes)
			(layer "F.Fab")
			(hide yes)
			(effects
				(font
					(size 1.016 1.016)
					(thickness 0.1524)
				)
			)
		)
		(property "Device Type" "C402H22"
			(at 1.1811 -4.2291 0)
			(unlocked yes)
			(layer "F.Fab")
			(hide yes)
			(effects
				(font
					(size 1.016 1.016)
					(thickness 0.1524)
				)
			)
		)
		(duplicate_pad_numbers_are_jumpers no)
		(fp_rect
			(start -0.4318 0.9525)
			(end 0.4318 -0.9525)
			(stroke
				(width 0)
				(type default)
			)
			(fill no)
			(layer "F.CrtYd")
		)
		(fp_rect
			(start -0.4318 0.9525)
			(end 0.4318 -0.9525)
			(stroke
				(width 0)
				(type default)
			)
			(fill no)
			(layer "F.Fab")
		)
		(pad "1" smd custom
			(at 0 -0.4445)
			(size 0.1524 0.1524)
			(layers "F.Cu" "F.Mask" "F.Paste")
			(net "PCIE_TX_CAP_N82")
			(options
				(clearance outline)
				(anchor circle)
			)
			(primitives
				(gr_poly
					(pts
						(arc
							(start 0.3048 -0.2032)
							(mid 0.275042 -0.275042)
							(end 0.2032 -0.3048)
						)
						(arc
							(start -0.2032 -0.3048)
							(mid -0.275042 -0.275042)
							(end -0.3048 -0.2032)
						)
						(arc
							(start -0.3048 0.2032)
							(mid -0.275042 0.275042)
							(end -0.2032 0.3048)
						)
						(arc
							(start 0.2032 0.3048)
							(mid 0.275042 0.275042)
							(end 0.3048 0.2032)
						)
					)
					(width 0)
					(fill yes)
				)
			)
		)
		(pad "2" smd custom
			(at 0 0.4445)
			(size 0.1524 0.1524)
			(layers "F.Cu" "F.Mask" "F.Paste")
			(net "PCIE_TX_N82")
			(options
				(clearance outline)
				(anchor circle)
			)
			(primitives
				(gr_poly
					(pts
						(arc
							(start 0.3048 -0.2032)
							(mid 0.275042 -0.275042)
							(end 0.2032 -0.3048)
						)
						(arc
							(start -0.2032 -0.3048)
							(mid -0.275042 -0.275042)
							(end -0.3048 -0.2032)
						)
						(arc
							(start -0.3048 0.2032)
							(mid -0.275042 0.275042)
							(end -0.2032 0.3048)
						)
						(arc
							(start 0.2032 0.3048)
							(mid 0.275042 0.275042)
							(end 0.3048 0.2032)
						)
					)
					(width 0)
					(fill yes)
				)
			)
		)
	)
	(footprint ""
		(layer "F.Cu")
		(at 42.545 -204.216 90)
		(property "Reference" "C699"
			(at 0 0 90)
			(layer "F.SilkS")
			(hide yes)
			(effects
				(font
					(size 1.27 1.27)
				)
			)
		)
		(property "Value" "SC220P50V3JN-GP"
			(at 0 -2.8194 90)
			(unlocked yes)
			(layer "F.Fab")
			(hide yes)
			(effects
				(font
					(size 1.016 1.016)
					(thickness 0.1524)
				)
			)
		)
		(property "Device Type" "C603H36"
			(at 0 -4.3434 90)
			(unlocked yes)
			(layer "F.Fab")
			(hide yes)
			(effects
				(font
					(size 1.016 1.016)
					(thickness 0.1524)
				)
			)
		)
		(duplicate_pad_numbers_are_jumpers no)
		(fp_line
			(start 0.508 0)
			(end -0.508 0)
			(stroke
				(width 0.2032)
				(type default)
			)
			(layer "F.SilkS")
		)
		(fp_rect
			(start -0.5842 1.3335)
			(end 0.5842 -1.3335)
			(stroke
				(width 0)
				(type default)
			)
			(fill no)
			(layer "F.CrtYd")
		)
		(fp_rect
			(start -0.5842 1.3335)
			(end 0.5842 -1.3335)
			(stroke
				(width 0)
				(type default)
			)
			(fill no)
			(layer "F.Fab")
		)
		(pad "1" smd custom
			(at 0 -0.762 90)
			(size 0.2159 0.2159)
			(layers "F.Cu" "F.Mask" "F.Paste")
			(net "BUF_I2C6_C_FCB_SCL_R")
			(options
				(clearance outline)
				(anchor circle)
			)
			(primitives
				(gr_poly
					(pts
						(arc
							(start -0.3302 -0.4318)
							(mid -0.402042 -0.402042)
							(end -0.4318 -0.3302)
						)
						(arc
							(start -0.4318 0.3302)
							(mid -0.402042 0.402042)
							(end -0.3302 0.4318)
						)
						(arc
							(start 0.3302 0.4318)
							(mid 0.402042 0.402042)
							(end 0.4318 0.3302)
						)
						(arc
							(start 0.4318 -0.3302)
							(mid 0.402042 -0.402042)
							(end 0.3302 -0.4318)
						)
					)
					(width 0)
					(fill yes)
				)
			)
		)
		(pad "2" smd custom
			(at 0 0.762 90)
			(size 0.2159 0.2159)
			(layers "F.Cu" "F.Mask" "F.Paste")
			(net "GND")
			(options
				(clearance outline)
				(anchor circle)
			)
			(primitives
				(gr_poly
					(pts
						(arc
							(start -0.3302 -0.4318)
							(mid -0.402042 -0.402042)
							(end -0.4318 -0.3302)
						)
						(arc
							(start -0.4318 0.3302)
							(mid -0.402042 0.402042)
							(end -0.3302 0.4318)
						)
						(arc
							(start 0.3302 0.4318)
							(mid 0.402042 0.402042)
							(end 0.4318 0.3302)
						)
						(arc
							(start 0.4318 -0.3302)
							(mid 0.402042 -0.402042)
							(end 0.3302 -0.4318)
						)
					)
					(width 0)
					(fill yes)
				)
			)
		)
	)
	(footprint ""
		(layer "F.Cu")
		(at 16.764 -150.495 180)
		(property "Reference" "R491"
			(at 0 0 180)
			(layer "F.SilkS")
			(hide yes)
			(effects
				(font
					(size 1.27 1.27)
				)
			)
		)
		(property "Value" "0R2J-2-GP"
			(at 0.064008 -3.993896 180)
			(unlocked yes)
			(layer "F.Fab")
			(hide yes)
			(effects
				(font
					(size 1.016 1.016)
					(thickness 0.1524)
				)
			)
		)
		(property "Device Type" "R402H16"
			(at 0.064008 -5.517896 180)
			(unlocked yes)
			(layer "F.Fab")
			(hide yes)
			(effects
				(font
					(size 1.016 1.016)
					(thickness 0.1524)
				)
			)
		)
		(duplicate_pad_numbers_are_jumpers no)
		(fp_line
			(start 0.508 -0.9398)
			(end -0.508 -0.9398)
			(stroke
				(width 0.1524)
				(type default)
			)
			(layer "F.SilkS")
		)
		(fp_line
			(start -0.508 -0.9398)
			(end -0.508 0.9398)
			(stroke
				(width 0.1524)
				(type default)
			)
			(layer "F.SilkS")
		)
		(fp_rect
			(start -0.508 0.9398)
			(end 0.508 -0.9398)
			(stroke
				(width 0)
				(type default)
			)
			(fill no)
			(layer "F.CrtYd")
		)
		(fp_rect
			(start -0.508 0.9398)
			(end 0.508 -0.9398)
			(stroke
				(width 0)
				(type default)
			)
			(fill no)
			(layer "F.Fab")
		)
		(pad "1" smd custom
			(at 0 -0.4445 180)
			(size 0.1397 0.1397)
			(layers "F.Cu" "F.Mask" "F.Paste")
			(net "RST_BMC_DDR3_R_N")
			(options
				(clearance outline)
				(anchor circle)
			)
			(primitives
				(gr_poly
					(pts
						(arc
							(start -0.1778 -0.2794)
							(mid -0.249642 -0.249642)
							(end -0.2794 -0.1778)
						)
						(arc
							(start -0.2794 0.1778)
							(mid -0.249642 0.249642)
							(end -0.1778 0.2794)
						)
						(arc
							(start 0.1778 0.2794)
							(mid 0.249642 0.249642)
							(end 0.2794 0.1778)
						)
						(arc
							(start 0.2794 -0.1778)
							(mid 0.249642 -0.249642)
							(end 0.1778 -0.2794)
						)
					)
					(width 0)
					(fill yes)
				)
			)
		)
		(pad "2" smd custom
			(at 0 0.4445 180)
			(size 0.1397 0.1397)
			(layers "F.Cu" "F.Mask" "F.Paste")
			(net "BMC_DDR3_RST_N")
			(options
				(clearance outline)
				(anchor circle)
			)
			(primitives
				(gr_poly
					(pts
						(arc
							(start -0.1778 -0.2794)
							(mid -0.249642 -0.249642)
							(end -0.2794 -0.1778)
						)
						(arc
							(start -0.2794 0.1778)
							(mid -0.249642 0.249642)
							(end -0.1778 0.2794)
						)
						(arc
							(start 0.1778 0.2794)
							(mid 0.249642 0.249642)
							(end 0.2794 0.1778)
						)
						(arc
							(start 0.2794 -0.1778)
							(mid 0.249642 -0.249642)
							(end 0.1778 -0.2794)
						)
					)
					(width 0)
					(fill yes)
				)
			)
		)
	)
	(footprint ""
		(layer "F.Cu")
		(at 133.072124 -196.443092)
		(property "Reference" "R7974"
			(at 0 0 0)
			(layer "F.SilkS")
			(hide yes)
			(effects
				(font
					(size 1.27 1.27)
				)
			)
		)
		(property "Value" "0R2J-2-GP"
			(at 0.064008 -3.993896 0)
			(unlocked yes)
			(layer "F.Fab")
			(hide yes)
			(effects
				(font
					(size 1.016 1.016)
					(thickness 0.1524)
				)
			)
		)
		(property "Device Type" "R402H16"
			(at 0.064008 -5.517896 0)
			(unlocked yes)
			(layer "F.Fab")
			(hide yes)
			(effects
				(font
					(size 1.016 1.016)
					(thickness 0.1524)
				)
			)
		)
		(duplicate_pad_numbers_are_jumpers no)
		(fp_line
			(start -0.508 -0.9398)
			(end -0.508 0.9398)
			(stroke
				(width 0.1524)
				(type default)
			)
			(layer "F.SilkS")
		)
		(fp_line
			(start 0.508 -0.9398)
			(end -0.508 -0.9398)
			(stroke
				(width 0.1524)
				(type default)
			)
			(layer "F.SilkS")
		)
		(fp_rect
			(start -0.508 0.9398)
			(end 0.508 -0.9398)
			(stroke
				(width 0)
				(type default)
			)
			(fill no)
			(layer "F.CrtYd")
		)
		(fp_rect
			(start -0.508 0.9398)
			(end 0.508 -0.9398)
			(stroke
				(width 0)
				(type default)
			)
			(fill no)
			(layer "F.Fab")
		)
		(pad "1" smd custom
			(at 0 -0.4445)
			(size 0.1397 0.1397)
			(layers "F.Cu" "F.Mask" "F.Paste")
			(net "SSD_PERST#2")
			(options
				(clearance outline)
				(anchor circle)
			)
			(primitives
				(gr_poly
					(pts
						(arc
							(start -0.1778 -0.2794)
							(mid -0.249642 -0.249642)
							(end -0.2794 -0.1778)
						)
						(arc
							(start -0.2794 0.1778)
							(mid -0.249642 0.249642)
							(end -0.1778 0.2794)
						)
						(arc
							(start 0.1778 0.2794)
							(mid 0.249642 0.249642)
							(end 0.2794 0.1778)
						)
						(arc
							(start 0.2794 -0.1778)
							(mid 0.249642 -0.249642)
							(end 0.1778 -0.2794)
						)
					)
					(width 0)
					(fill yes)
				)
			)
		)
		(pad "2" smd custom
			(at 0 0.4445)
			(size 0.1397 0.1397)
			(layers "F.Cu" "F.Mask" "F.Paste")
			(net "SSD_PERST#2_R")
			(options
				(clearance outline)
				(anchor circle)
			)
			(primitives
				(gr_poly
					(pts
						(arc
							(start -0.1778 -0.2794)
							(mid -0.249642 -0.249642)
							(end -0.2794 -0.1778)
						)
						(arc
							(start -0.2794 0.1778)
							(mid -0.249642 0.249642)
							(end -0.1778 0.2794)
						)
						(arc
							(start 0.1778 0.2794)
							(mid 0.249642 0.249642)
							(end 0.2794 0.1778)
						)
						(arc
							(start 0.2794 -0.1778)
							(mid 0.249642 -0.249642)
							(end 0.1778 -0.2794)
						)
					)
					(width 0)
					(fill yes)
				)
			)
		)
	)
)
